# S9S_MB_2U (Grand Teton) — schematic netlist excerpt (pin names and nets, part order shuffled) for the footprints in the layout excerpt that follows; sources: Cadence DE-HDL packaged netlist, KiCad conversion of 03242023_DA0F0TMBIJ0_F0T_Motherboard_J_brd_V01_OCP.brd

C992  Q_CAP  10UF 6.3V 20% X6S  pkg C0402  page 74 : A = PVCCIN_CPU0 ; B = GND

Y9  Q_XTAL_4P_13BI_24GND  12MHZ EMPTY  pkg OSC4_DNCA250000ETS_2-5X2_H26  page 196
  X1  = USB_HUB_2_XTAL_IN
  G1  = GND
  X2  = USB_HUB_2_XTAL_OUT
  G2  = GND

(kicad_pcb
	(version 20260206)
	(generator "pcbnew")
	(generator_version "10.0")
	(general
		(thickness 1.6)
		(legacy_teardrops no)
	)
	(paper "A4")
	(title_block
		(title "03242023_DA0F0TMBIJ0_F0T_Motherboard_J_brd_V01_OCP.brd")
		(comment 1 "Grand Teton / footprints 2881-2882 of 6105")
	)
	(layers
		(0 "F.Cu" signal "TOP")
		(4 "In1.Cu" signal "GND")
		(6 "In2.Cu" signal "IN1")
		(8 "In3.Cu" signal "GND1")
		(10 "In4.Cu" signal "IN2")
		(12 "In5.Cu" signal "GND2")
		(14 "In6.Cu" signal "IN3")
		(16 "In7.Cu" signal "GND3")
		(18 "In8.Cu" signal "VCC")
		(20 "In9.Cu" signal "VCC1")
		(22 "In10.Cu" signal "GND4")
		(24 "In11.Cu" signal "IN4")
		(26 "In12.Cu" signal "GND5")
		(28 "In13.Cu" signal "IN5")
		(30 "In14.Cu" signal "GND6")
		(32 "In15.Cu" signal "IN6")
		(34 "In16.Cu" signal "GND7")
		(2 "B.Cu" signal "BOTTOM")
		(9 "F.Adhes" user "F.Adhesive")
		(11 "B.Adhes" user "B.Adhesive")
		(13 "F.Paste" user "Package Geometry/Pastemask Top")
		(15 "B.Paste" user "Package Geometry/Pastemask Bottom")
		(5 "F.SilkS" user "Ref Des/Silkscreen Top")
		(7 "B.SilkS" user "Ref Des/Silkscreen Bottom")
		(1 "F.Mask" user "Board Geometry/Soldermask Top")
		(3 "B.Mask" user "Board Geometry/Soldermask Bottom")
		(17 "Dwgs.User" user "User.Drawings")
		(19 "Cmts.User" user "User.Comments")
		(21 "Eco1.User" user "User.Eco1")
		(23 "Eco2.User" user "User.Eco2")
		(25 "Edge.Cuts" user "Board Geometry/Outline")
		(27 "Margin" user)
		(31 "F.CrtYd" user "Package Geometry/Place Bound Top")
		(29 "B.CrtYd" user "Package Geometry/Place Bound Bottom")
		(35 "F.Fab" user "Ref Des/Assembly Top")
		(33 "B.Fab" user "Ref Des/Assembly Bottom")
	)
	(footprint ""
		(layer "F.Cu")
		(at 150.04796 -37.904166)
		(property "Reference" "Y9"
			(at -1.3462 -2.174748 0)
			(unlocked yes)
			(layer "F.SilkS")
			(effects
				(font
					(size 0.7874 0.5842)
					(thickness 0.1524)
				)
				(justify left)
			)
		)
		(property "Value" ""
			(at 0 0 0)
			(layer "F.Fab")
			(effects
				(font
					(size 1.27 1.27)
				)
			)
		)
		(duplicate_pad_numbers_are_jumpers no)
		(fp_line
			(start -1.2446 -1.4986)
			(end -1.2446 1.4986)
			(stroke
				(width 0.1524)
				(type default)
			)
			(layer "F.SilkS")
		)
		(fp_line
			(start -1.2446 1.4986)
			(end 1.2446 1.4986)
			(stroke
				(width 0.1524)
				(type default)
			)
			(layer "F.SilkS")
		)
		(fp_line
			(start 1.2446 -1.4986)
			(end -1.2446 -1.4986)
			(stroke
				(width 0.1524)
				(type default)
			)
			(layer "F.SilkS")
		)
		(fp_line
			(start 1.2446 1.4986)
			(end 1.2446 -1.4986)
			(stroke
				(width 0.1524)
				(type default)
			)
			(layer "F.SilkS")
		)
		(fp_poly
			(pts
				(xy -2.4638 -1.357884) (xy -1.4478 -0.849884) (xy -2.4638 -0.341884)
			)
			(stroke
				(width 0)
				(type default)
			)
			(fill yes)
			(layer "F.SilkS")
		)
		(fp_line
			(start -1.050036 -1.299972)
			(end -1.050036 1.299972)
			(stroke
				(width 0.1)
				(type default)
			)
			(layer "F.Fab")
		)
		(fp_line
			(start -1.050036 1.299972)
			(end 1.050036 1.299972)
			(stroke
				(width 0.1)
				(type default)
			)
			(layer "F.Fab")
		)
		(fp_line
			(start 1.050036 -1.299972)
			(end -1.050036 -1.299972)
			(stroke
				(width 0.1)
				(type default)
			)
			(layer "F.Fab")
		)
		(fp_line
			(start 1.050036 1.299972)
			(end 1.050036 -1.299972)
			(stroke
				(width 0.1)
				(type default)
			)
			(layer "F.Fab")
		)
		(fp_poly
			(pts
				(xy -2.4638 -1.357884) (xy -2.4638 -0.341884) (xy -1.4478 -0.849884)
			)
			(stroke
				(width 0)
				(type default)
			)
			(fill yes)
			(layer "F.Fab")
		)
		(pad "1" smd rect
			(at -0.649986 -0.849884 180)
			(size 0.9144 1.016)
			(layers "F.Cu" "F.Mask" "F.Paste")
			(net "USB_HUB_2_XTAL_IN")
		)
		(pad "2" smd rect
			(at -0.649986 0.849884 180)
			(size 0.9144 1.016)
			(layers "F.Cu" "F.Mask" "F.Paste")
			(net "GND")
		)
		(pad "3" smd rect
			(at 0.649986 0.849884 180)
			(size 0.9144 1.016)
			(layers "F.Cu" "F.Mask" "F.Paste")
			(net "USB_HUB_2_XTAL_OUT")
		)
		(pad "4" smd rect
			(at 0.649986 -0.849884 180)
			(size 0.9144 1.016)
			(layers "F.Cu" "F.Mask" "F.Paste")
			(net "GND")
		)
	)
	(footprint ""
		(layer "F.Cu")
		(at 366.48263 -256.654046 -90)
		(property "Reference" "C992"
			(at 0 0 270)
			(layer "F.SilkS")
			(hide yes)
			(effects
				(font
					(size 1.27 1.27)
				)
			)
		)
		(property "Value" ""
			(at 0 0 270)
			(layer "F.Fab")
			(effects
				(font
					(size 1.27 1.27)
				)
			)
		)
		(duplicate_pad_numbers_are_jumpers no)
		(fp_line
			(start -0.7874 0.4064)
			(end -0.7874 -0.4064)
			(stroke
				(width 0.1524)
				(type default)
			)
			(layer "F.SilkS")
		)
		(fp_line
			(start 0.7874 0.4064)
			(end -0.7874 0.4064)
			(stroke
				(width 0.1524)
				(type default)
			)
			(layer "F.SilkS")
		)
		(fp_line
			(start -0.7874 -0.4064)
			(end 0.7874 -0.4064)
			(stroke
				(width 0.1524)
				(type default)
			)
			(layer "F.SilkS")
		)
		(fp_line
			(start 0.7874 -0.4064)
			(end 0.7874 0.4064)
			(stroke
				(width 0.1524)
				(type default)
			)
			(layer "F.SilkS")
		)
		(fp_line
			(start -0.67945 0.3048)
			(end -0.67945 -0.305054)
			(stroke
				(width 0.1)
				(type default)
			)
			(layer "F.Fab")
		)
		(fp_line
			(start -0.12065 0.3048)
			(end -0.67945 0.3048)
			(stroke
				(width 0.1)
				(type default)
			)
			(layer "F.Fab")
		)
		(fp_line
			(start 0.120396 0.3048)
			(end 0.120396 0.2794)
			(stroke
				(width 0.1)
				(type default)
			)
			(layer "F.Fab")
		)
		(fp_line
			(start 0.67945 0.3048)
			(end 0.120396 0.3048)
			(stroke
				(width 0.1)
				(type default)
			)
			(layer "F.Fab")
		)
		(fp_line
			(start -0.12065 0.2794)
			(end -0.12065 0.3048)
			(stroke
				(width 0.1)
				(type default)
			)
			(layer "F.Fab")
		)
		(fp_line
			(start 0.120396 0.2794)
			(end -0.12065 0.2794)
			(stroke
				(width 0.1)
				(type default)
			)
			(layer "F.Fab")
		)
		(fp_line
			(start -0.12065 -0.2794)
			(end 0.12065 -0.2794)
			(stroke
				(width 0.1)
				(type default)
			)
			(layer "F.Fab")
		)
		(fp_line
			(start 0.12065 -0.2794)
			(end 0.12065 -0.3048)
			(stroke
				(width 0.1)
				(type default)
			)
			(layer "F.Fab")
		)
		(fp_line
			(start 0.12065 -0.3048)
			(end 0.67945 -0.3048)
			(stroke
				(width 0.1)
				(type default)
			)
			(layer "F.Fab")
		)
		(fp_line
			(start 0.67945 -0.3048)
			(end 0.67945 0.3048)
			(stroke
				(width 0.1)
				(type default)
			)
			(layer "F.Fab")
		)
		(fp_line
			(start -0.67945 -0.305054)
			(end -0.12065 -0.305054)
			(stroke
				(width 0.1)
				(type default)
			)
			(layer "F.Fab")
		)
		(fp_line
			(start -0.12065 -0.305054)
			(end -0.12065 -0.2794)
			(stroke
				(width 0.1)
				(type default)
			)
			(layer "F.Fab")
		)
		(pad "1" smd circle
			(at -0.40005 0 270)
			(size 0 0)
			(layers "F.Cu" "F.Mask" "F.Paste")
			(net "PVCCIN_CPU0")
		)
		(pad "2" smd circle
			(at 0.40005 0 270)
			(size 0 0)
			(layers "F.Cu" "F.Mask" "F.Paste")
			(net "GND")
		)
	)
)
